(kicad_pcb
	(version 20260206)
	(generator "pcbnew")
	(generator_version "10.0")
	(general
		(thickness 1.6)
		(legacy_teardrops no)
	)
	(paper "A4")
	(title_block
		(title "04192023_DAF0TMB3IC0_F0TG_MB_C_brd_V02_OCP.brd")
		(comment 1 "Grand Teton / footprints 8247-8253 of 8354")
	)
	(layers
		(0 "F.Cu" signal "TOP")
		(4 "In1.Cu" signal "GND")
		(6 "In2.Cu" signal "IN1")
		(8 "In3.Cu" signal "GND1")
		(10 "In4.Cu" signal "IN2")
		(12 "In5.Cu" signal "GND2")
		(14 "In6.Cu" signal "IN3")
		(16 "In7.Cu" signal "GND3")
		(18 "In8.Cu" signal "VCC")
		(20 "In9.Cu" signal "VCC1")
		(22 "In10.Cu" signal "GND4")
		(24 "In11.Cu" signal "IN4")
		(26 "In12.Cu" signal "GND5")
		(28 "In13.Cu" signal "IN5")
		(30 "In14.Cu" signal "GND6")
		(32 "In15.Cu" signal "IN6")
		(34 "In16.Cu" signal "GND7")
		(2 "B.Cu" signal "BOTTOM")
		(9 "F.Adhes" user "F.Adhesive")
		(11 "B.Adhes" user "B.Adhesive")
		(13 "F.Paste" user "Package Geometry/Pastemask Top")
		(15 "B.Paste" user "Package Geometry/Pastemask Bottom")
		(5 "F.SilkS" user "Ref Des/Silkscreen Top")
		(7 "B.SilkS" user "Ref Des/Silkscreen Bottom")
		(1 "F.Mask" user "Board Geometry/Soldermask Top")
		(3 "B.Mask" user "Board Geometry/Soldermask Bottom")
		(17 "Dwgs.User" user "User.Drawings")
		(19 "Cmts.User" user "User.Comments")
		(21 "Eco1.User" user "User.Eco1")
		(23 "Eco2.User" user "User.Eco2")
		(25 "Edge.Cuts" user "Board Geometry/Outline")
		(27 "Margin" user)
		(31 "F.CrtYd" user "Package Geometry/Place Bound Top")
		(29 "B.CrtYd" user "Package Geometry/Place Bound Bottom")
		(35 "F.Fab" user "Ref Des/Assembly Top")
		(33 "B.Fab" user "Ref Des/Assembly Bottom")
	)
	(footprint ""
		(layer "B.Cu")
		(at 241.173 -222.25 -90)
		(property "Reference" "C611"
			(at 0 0 90)
			(layer "B.SilkS")
			(hide yes)
			(effects
				(font
					(size 1.27 1.27)
				)
				(justify mirror)
			)
		)
		(property "Value" ""
			(at 0 0 90)
			(layer "B.Fab")
			(effects
				(font
					(size 1.27 1.27)
				)
				(justify mirror)
			)
		)
		(duplicate_pad_numbers_are_jumpers no)
		(fp_line
			(start -0.7874 0.4064)
			(end 0.7874 0.4064)
			(stroke
				(width 0.1524)
				(type default)
			)
			(layer "B.SilkS")
		)
		(fp_line
			(start 0.7874 0.4064)
			(end 0.7874 -0.4064)
			(stroke
				(width 0.1524)
				(type default)
			)
			(layer "B.SilkS")
		)
		(fp_line
			(start -0.7874 -0.4064)
			(end -0.7874 0.4064)
			(stroke
				(width 0.1524)
				(type default)
			)
			(layer "B.SilkS")
		)
		(fp_line
			(start 0.7874 -0.4064)
			(end -0.7874 -0.4064)
			(stroke
				(width 0.1524)
				(type default)
			)
			(layer "B.SilkS")
		)
		(fp_line
			(start -0.67945 0.3048)
			(end -0.120396 0.3048)
			(stroke
				(width 0.1)
				(type default)
			)
			(layer "B.Fab")
		)
		(fp_line
			(start -0.120396 0.3048)
			(end -0.120396 0.2794)
			(stroke
				(width 0.1)
				(type default)
			)
			(layer "B.Fab")
		)
		(fp_line
			(start 0.12065 0.3048)
			(end 0.67945 0.3048)
			(stroke
				(width 0.1)
				(type default)
			)
			(layer "B.Fab")
		)
		(fp_line
			(start 0.67945 0.3048)
			(end 0.67945 -0.305054)
			(stroke
				(width 0.1)
				(type default)
			)
			(layer "B.Fab")
		)
		(fp_line
			(start -0.120396 0.2794)
			(end 0.12065 0.2794)
			(stroke
				(width 0.1)
				(type default)
			)
			(layer "B.Fab")
		)
		(fp_line
			(start 0.12065 0.2794)
			(end 0.12065 0.3048)
			(stroke
				(width 0.1)
				(type default)
			)
			(layer "B.Fab")
		)
		(fp_line
			(start -0.12065 -0.2794)
			(end -0.12065 -0.3048)
			(stroke
				(width 0.1)
				(type default)
			)
			(layer "B.Fab")
		)
		(fp_line
			(start 0.12065 -0.2794)
			(end -0.12065 -0.2794)
			(stroke
				(width 0.1)
				(type default)
			)
			(layer "B.Fab")
		)
		(fp_line
			(start -0.67945 -0.3048)
			(end -0.67945 0.3048)
			(stroke
				(width 0.1)
				(type default)
			)
			(layer "B.Fab")
		)
		(fp_line
			(start -0.12065 -0.3048)
			(end -0.67945 -0.3048)
			(stroke
				(width 0.1)
				(type default)
			)
			(layer "B.Fab")
		)
		(fp_line
			(start 0.12065 -0.305054)
			(end 0.12065 -0.2794)
			(stroke
				(width 0.1)
				(type default)
			)
			(layer "B.Fab")
		)
		(fp_line
			(start 0.67945 -0.305054)
			(end 0.12065 -0.305054)
			(stroke
				(width 0.1)
				(type default)
			)
			(layer "B.Fab")
		)
		(pad "1" smd circle
			(at 0.40005 0 90)
			(size 0 0)
			(layers "B.Cu" "B.Mask" "B.Paste")
			(net "P3V3_AUX")
		)
		(pad "2" smd circle
			(at -0.40005 0 90)
			(size 0 0)
			(layers "B.Cu" "B.Mask" "B.Paste")
			(net "GND")
		)
	)
	(footprint ""
		(layer "B.Cu")
		(at 79.015082 -391.340848 -90)
		(property "Reference" "C336"
			(at 0 0 90)
			(layer "B.SilkS")
			(hide yes)
			(effects
				(font
					(size 1.27 1.27)
				)
				(justify mirror)
			)
		)
		(property "Value" ""
			(at 0 0 90)
			(layer "B.Fab")
			(effects
				(font
					(size 1.27 1.27)
				)
				(justify mirror)
			)
		)
		(duplicate_pad_numbers_are_jumpers no)
		(fp_line
			(start -0.7874 0.4064)
			(end 0.7874 0.4064)
			(stroke
				(width 0.1524)
				(type default)
			)
			(layer "B.SilkS")
		)
		(fp_line
			(start 0.7874 0.4064)
			(end 0.7874 -0.4064)
			(stroke
				(width 0.1524)
				(type default)
			)
			(layer "B.SilkS")
		)
		(fp_line
			(start -0.7874 -0.4064)
			(end -0.7874 0.4064)
			(stroke
				(width 0.1524)
				(type default)
			)
			(layer "B.SilkS")
		)
		(fp_line
			(start 0.7874 -0.4064)
			(end -0.7874 -0.4064)
			(stroke
				(width 0.1524)
				(type default)
			)
			(layer "B.SilkS")
		)
		(fp_line
			(start -0.67945 0.3048)
			(end -0.120396 0.3048)
			(stroke
				(width 0.1)
				(type default)
			)
			(layer "B.Fab")
		)
		(fp_line
			(start -0.120396 0.3048)
			(end -0.120396 0.2794)
			(stroke
				(width 0.1)
				(type default)
			)
			(layer "B.Fab")
		)
		(fp_line
			(start 0.12065 0.3048)
			(end 0.67945 0.3048)
			(stroke
				(width 0.1)
				(type default)
			)
			(layer "B.Fab")
		)
		(fp_line
			(start 0.67945 0.3048)
			(end 0.67945 -0.305054)
			(stroke
				(width 0.1)
				(type default)
			)
			(layer "B.Fab")
		)
		(fp_line
			(start -0.120396 0.2794)
			(end 0.12065 0.2794)
			(stroke
				(width 0.1)
				(type default)
			)
			(layer "B.Fab")
		)
		(fp_line
			(start 0.12065 0.2794)
			(end 0.12065 0.3048)
			(stroke
				(width 0.1)
				(type default)
			)
			(layer "B.Fab")
		)
		(fp_line
			(start -0.12065 -0.2794)
			(end -0.12065 -0.3048)
			(stroke
				(width 0.1)
				(type default)
			)
			(layer "B.Fab")
		)
		(fp_line
			(start 0.12065 -0.2794)
			(end -0.12065 -0.2794)
			(stroke
				(width 0.1)
				(type default)
			)
			(layer "B.Fab")
		)
		(fp_line
			(start -0.67945 -0.3048)
			(end -0.67945 0.3048)
			(stroke
				(width 0.1)
				(type default)
			)
			(layer "B.Fab")
		)
		(fp_line
			(start -0.12065 -0.3048)
			(end -0.67945 -0.3048)
			(stroke
				(width 0.1)
				(type default)
			)
			(layer "B.Fab")
		)
		(fp_line
			(start 0.12065 -0.305054)
			(end 0.12065 -0.2794)
			(stroke
				(width 0.1)
				(type default)
			)
			(layer "B.Fab")
		)
		(fp_line
			(start 0.67945 -0.305054)
			(end 0.12065 -0.305054)
			(stroke
				(width 0.1)
				(type default)
			)
			(layer "B.Fab")
		)
		(pad "1" smd circle
			(at 0.40005 0 90)
			(size 0 0)
			(layers "B.Cu" "B.Mask" "B.Paste")
			(net "P0V9_CPU1_RT1_2A")
		)
		(pad "2" smd circle
			(at -0.40005 0 90)
			(size 0 0)
			(layers "B.Cu" "B.Mask" "B.Paste")
			(net "GND")
		)
	)
	(footprint ""
		(layer "B.Cu")
		(at 24.765 -365.76 180)
		(property "Reference" "R8234"
			(at 0 0 0)
			(layer "B.SilkS")
			(hide yes)
			(effects
				(font
					(size 1.27 1.27)
				)
				(justify mirror)
			)
		)
		(property "Value" ""
			(at 0 0 0)
			(layer "B.Fab")
			(effects
				(font
					(size 1.27 1.27)
				)
				(justify mirror)
			)
		)
		(duplicate_pad_numbers_are_jumpers no)
		(fp_line
			(start 0.7874 0.4064)
			(end 0.7874 -0.4064)
			(stroke
				(width 0.1524)
				(type default)
			)
			(layer "B.SilkS")
		)
		(fp_line
			(start 0.7874 -0.4064)
			(end -0.7874 -0.4064)
			(stroke
				(width 0.1524)
				(type default)
			)
			(layer "B.SilkS")
		)
		(fp_line
			(start -0.7874 0.4064)
			(end 0.7874 0.4064)
			(stroke
				(width 0.1524)
				(type default)
			)
			(layer "B.SilkS")
		)
		(fp_line
			(start -0.7874 -0.4064)
			(end -0.7874 0.4064)
			(stroke
				(width 0.1524)
				(type default)
			)
			(layer "B.SilkS")
		)
		(fp_line
			(start 0.67945 0.3048)
			(end 0.67945 -0.305054)
			(stroke
				(width 0.1)
				(type default)
			)
			(layer "B.Fab")
		)
		(fp_line
			(start 0.67945 -0.305054)
			(end 0.12065 -0.305054)
			(stroke
				(width 0.1)
				(type default)
			)
			(layer "B.Fab")
		)
		(fp_line
			(start 0.12065 0.3048)
			(end 0.67945 0.3048)
			(stroke
				(width 0.1)
				(type default)
			)
			(layer "B.Fab")
		)
		(fp_line
			(start 0.12065 0.2794)
			(end 0.12065 0.3048)
			(stroke
				(width 0.1)
				(type default)
			)
			(layer "B.Fab")
		)
		(fp_line
			(start 0.12065 -0.2794)
			(end -0.12065 -0.2794)
			(stroke
				(width 0.1)
				(type default)
			)
			(layer "B.Fab")
		)
		(fp_line
			(start 0.12065 -0.305054)
			(end 0.12065 -0.2794)
			(stroke
				(width 0.1)
				(type default)
			)
			(layer "B.Fab")
		)
		(fp_line
			(start -0.120396 0.3048)
			(end -0.120396 0.2794)
			(stroke
				(width 0.1)
				(type default)
			)
			(layer "B.Fab")
		)
		(fp_line
			(start -0.120396 0.2794)
			(end 0.12065 0.2794)
			(stroke
				(width 0.1)
				(type default)
			)
			(layer "B.Fab")
		)
		(fp_line
			(start -0.12065 -0.2794)
			(end -0.12065 -0.3048)
			(stroke
				(width 0.1)
				(type default)
			)
			(layer "B.Fab")
		)
		(fp_line
			(start -0.12065 -0.3048)
			(end -0.67945 -0.3048)
			(stroke
				(width 0.1)
				(type default)
			)
			(layer "B.Fab")
		)
		(fp_line
			(start -0.67945 0.3048)
			(end -0.120396 0.3048)
			(stroke
				(width 0.1)
				(type default)
			)
			(layer "B.Fab")
		)
		(fp_line
			(start -0.67945 -0.3048)
			(end -0.67945 0.3048)
			(stroke
				(width 0.1)
				(type default)
			)
			(layer "B.Fab")
		)
		(pad "1" smd circle
			(at 0.40005 0)
			(size 0 0)
			(layers "B.Cu" "B.Mask" "B.Paste")
			(net "PWRGD_PVDDCR_CPU1_P1")
		)
		(pad "2" smd circle
			(at -0.40005 0)
			(size 0 0)
			(layers "B.Cu" "B.Mask" "B.Paste")
			(net "PWRGD_PVDDCR_CPU1_P1_R")
		)
	)
	(footprint ""
		(layer "B.Cu")
		(at 106.184954 -174.340012 90)
		(property "Reference" "PC295_4"
			(at 0 0 90)
			(layer "B.SilkS")
			(hide yes)
			(effects
				(font
					(size 1.27 1.27)
				)
				(justify mirror)
			)
		)
		(property "Value" ""
			(at 0 0 90)
			(layer "B.Fab")
			(effects
				(font
					(size 1.27 1.27)
				)
				(justify mirror)
			)
		)
		(duplicate_pad_numbers_are_jumpers no)
		(fp_line
			(start 1.524 -0.762)
			(end -1.524 -0.762)
			(stroke
				(width 0.1524)
				(type default)
			)
			(layer "B.SilkS")
		)
		(fp_line
			(start -1.524 -0.762)
			(end -1.524 0.762)
			(stroke
				(width 0.1524)
				(type default)
			)
			(layer "B.SilkS")
		)
		(fp_line
			(start 1.524 0.762)
			(end 1.524 -0.762)
			(stroke
				(width 0.1524)
				(type default)
			)
			(layer "B.SilkS")
		)
		(fp_line
			(start -1.524 0.762)
			(end 1.524 0.762)
			(stroke
				(width 0.1524)
				(type default)
			)
			(layer "B.SilkS")
		)
		(fp_line
			(start 1.1049 -0.724916)
			(end 1.1049 0.724916)
			(stroke
				(width 0.1)
				(type default)
			)
			(layer "B.Fab")
		)
		(fp_line
			(start -1.1049 -0.724916)
			(end 1.1049 -0.724916)
			(stroke
				(width 0.1)
				(type default)
			)
			(layer "B.Fab")
		)
		(fp_line
			(start 1.1049 0.724916)
			(end -1.1049 0.724916)
			(stroke
				(width 0.1)
				(type default)
			)
			(layer "B.Fab")
		)
		(fp_line
			(start -1.1049 0.724916)
			(end -1.1049 -0.724916)
			(stroke
				(width 0.1)
				(type default)
			)
			(layer "B.Fab")
		)
		(pad "1" smd rect
			(at 0.889 0 90)
			(size 1.016 1.27)
			(layers "B.Cu" "B.Mask" "B.Paste")
			(net "SW_P12V_AUX_PVDDCR_CPU0_P1_FLT")
		)
		(pad "2" smd rect
			(at -0.889 0 90)
			(size 1.016 1.27)
			(layers "B.Cu" "B.Mask" "B.Paste")
			(net "GND")
		)
	)
	(footprint ""
		(layer "B.Cu")
		(at 99.111562 -386.766562 90)
		(property "Reference" "C353"
			(at 0 0 90)
			(layer "B.SilkS")
			(hide yes)
			(effects
				(font
					(size 1.27 1.27)
				)
				(justify mirror)
			)
		)
		(property "Value" ""
			(at 0 0 90)
			(layer "B.Fab")
			(effects
				(font
					(size 1.27 1.27)
				)
				(justify mirror)
			)
		)
		(duplicate_pad_numbers_are_jumpers no)
		(fp_line
			(start 0.299974 -0.150114)
			(end -0.299974 -0.150114)
			(stroke
				(width 0.1)
				(type default)
			)
			(layer "B.Fab")
		)
		(fp_line
			(start -0.299974 -0.150114)
			(end -0.299974 0.150114)
			(stroke
				(width 0.1)
				(type default)
			)
			(layer "B.Fab")
		)
		(fp_line
			(start 0.299974 0.150114)
			(end 0.299974 -0.150114)
			(stroke
				(width 0.1)
				(type default)
			)
			(layer "B.Fab")
		)
		(fp_line
			(start -0.299974 0.150114)
			(end 0.299974 0.150114)
			(stroke
				(width 0.1)
				(type default)
			)
			(layer "B.Fab")
		)
		(pad "1" smd rect
			(at 0.2667 0 270)
			(size 0.3048 0.381)
			(layers "B.Cu" "B.Mask" "B.Paste")
			(net "P0V9_CPU1_RT1_2A")
		)
		(pad "2" smd rect
			(at -0.2667 0 270)
			(size 0.3048 0.381)
			(layers "B.Cu" "B.Mask" "B.Paste")
			(net "GND")
		)
	)
	(footprint ""
		(layer "B.Cu")
		(at 322.7451 -398.942052 90)
		(property "Reference" "C575"
			(at 0 0 90)
			(layer "B.SilkS")
			(hide yes)
			(effects
				(font
					(size 1.27 1.27)
				)
				(justify mirror)
			)
		)
		(property "Value" ""
			(at 0 0 90)
			(layer "B.Fab")
			(effects
				(font
					(size 1.27 1.27)
				)
				(justify mirror)
			)
		)
		(duplicate_pad_numbers_are_jumpers no)
		(fp_line
			(start 0.7874 -0.4064)
			(end -0.7874 -0.4064)
			(stroke
				(width 0.1524)
				(type default)
			)
			(layer "B.SilkS")
		)
		(fp_line
			(start -0.7874 -0.4064)
			(end -0.7874 0.4064)
			(stroke
				(width 0.1524)
				(type default)
			)
			(layer "B.SilkS")
		)
		(fp_line
			(start 0.7874 0.4064)
			(end 0.7874 -0.4064)
			(stroke
				(width 0.1524)
				(type default)
			)
			(layer "B.SilkS")
		)
		(fp_line
			(start -0.7874 0.4064)
			(end 0.7874 0.4064)
			(stroke
				(width 0.1524)
				(type default)
			)
			(layer "B.SilkS")
		)
		(fp_line
			(start 0.67945 -0.305054)
			(end 0.12065 -0.305054)
			(stroke
				(width 0.1)
				(type default)
			)
			(layer "B.Fab")
		)
		(fp_line
			(start 0.12065 -0.305054)
			(end 0.12065 -0.2794)
			(stroke
				(width 0.1)
				(type default)
			)
			(layer "B.Fab")
		)
		(fp_line
			(start -0.12065 -0.3048)
			(end -0.67945 -0.3048)
			(stroke
				(width 0.1)
				(type default)
			)
			(layer "B.Fab")
		)
		(fp_line
			(start -0.67945 -0.3048)
			(end -0.67945 0.3048)
			(stroke
				(width 0.1)
				(type default)
			)
			(layer "B.Fab")
		)
		(fp_line
			(start 0.12065 -0.2794)
			(end -0.12065 -0.2794)
			(stroke
				(width 0.1)
				(type default)
			)
			(layer "B.Fab")
		)
		(fp_line
			(start -0.12065 -0.2794)
			(end -0.12065 -0.3048)
			(stroke
				(width 0.1)
				(type default)
			)
			(layer "B.Fab")
		)
		(fp_line
			(start 0.12065 0.2794)
			(end 0.12065 0.3048)
			(stroke
				(width 0.1)
				(type default)
			)
			(layer "B.Fab")
		)
		(fp_line
			(start -0.120396 0.2794)
			(end 0.12065 0.2794)
			(stroke
				(width 0.1)
				(type default)
			)
			(layer "B.Fab")
		)
		(fp_line
			(start 0.67945 0.3048)
			(end 0.67945 -0.305054)
			(stroke
				(width 0.1)
				(type default)
			)
			(layer "B.Fab")
		)
		(fp_line
			(start 0.12065 0.3048)
			(end 0.67945 0.3048)
			(stroke
				(width 0.1)
				(type default)
			)
			(layer "B.Fab")
		)
		(fp_line
			(start -0.120396 0.3048)
			(end -0.120396 0.2794)
			(stroke
				(width 0.1)
				(type default)
			)
			(layer "B.Fab")
		)
		(fp_line
			(start -0.67945 0.3048)
			(end -0.120396 0.3048)
			(stroke
				(width 0.1)
				(type default)
			)
			(layer "B.Fab")
		)
		(pad "1" smd circle
			(at 0.40005 0 270)
			(size 0 0)
			(layers "B.Cu" "B.Mask" "B.Paste")
			(net "P0V9_CPU0_RT0_2A")
		)
		(pad "2" smd circle
			(at -0.40005 0 270)
			(size 0 0)
			(layers "B.Cu" "B.Mask" "B.Paste")
			(net "GND")
		)
	)
	(footprint ""
		(layer "B.Cu")
		(at 385.018534 -396.393162 -90)
		(property "Reference" "C1055"
			(at 0 0 90)
			(layer "B.SilkS")
			(hide yes)
			(effects
				(font
					(size 1.27 1.27)
				)
				(justify mirror)
			)
		)
		(property "Value" ""
			(at 0 0 90)
			(layer "B.Fab")
			(effects
				(font
					(size 1.27 1.27)
				)
				(justify mirror)
			)
		)
		(duplicate_pad_numbers_are_jumpers no)
		(fp_line
			(start -0.299974 0.150114)
			(end 0.299974 0.150114)
			(stroke
				(width 0.1)
				(type default)
			)
			(layer "B.Fab")
		)
		(fp_line
			(start 0.299974 0.150114)
			(end 0.299974 -0.150114)
			(stroke
				(width 0.1)
				(type default)
			)
			(layer "B.Fab")
		)
		(fp_line
			(start -0.299974 -0.150114)
			(end -0.299974 0.150114)
			(stroke
				(width 0.1)
				(type default)
			)
			(layer "B.Fab")
		)
		(fp_line
			(start 0.299974 -0.150114)
			(end -0.299974 -0.150114)
			(stroke
				(width 0.1)
				(type default)
			)
			(layer "B.Fab")
		)
		(pad "1" smd rect
			(at 0.2667 0 90)
			(size 0.3048 0.381)
			(layers "B.Cu" "B.Mask" "B.Paste")
			(net "P0V9_CPU0_RT3_2A")
		)
		(pad "2" smd rect
			(at -0.2667 0 90)
			(size 0.3048 0.381)
			(layers "B.Cu" "B.Mask" "B.Paste")
			(net "GND")
		)
	)
)
